(kicad_pcb
	(version 20260206)
	(generator "pcbnew")
	(generator_version "10.0")
	(general
		(thickness 1.6)
		(legacy_teardrops no)
	)
	(paper "A4")
	(title_block
		(title "v1-chassis-manager — T6M_CM_d_v01_1031_1645.brd")
		(comment 1 "Open CloudServer (Microsoft) / footprints 1346-1355 of 2512")
	)
	(layers
		(0 "F.Cu" signal "TOP")
		(4 "In1.Cu" signal "GND1")
		(6 "In2.Cu" signal "IN1")
		(8 "In3.Cu" signal "VCC1")
		(10 "In4.Cu" signal "VCC2")
		(12 "In5.Cu" signal "GND2")
		(14 "In6.Cu" signal "IN2")
		(16 "In7.Cu" signal "IN3")
		(18 "In8.Cu" signal "GND3")
		(2 "B.Cu" signal "BOTTOM")
		(9 "F.Adhes" user "F.Adhesive")
		(11 "B.Adhes" user "B.Adhesive")
		(13 "F.Paste" user "Package Geometry/Pastemask Top")
		(15 "B.Paste" user "Package Geometry/Pastemask Bottom")
		(5 "F.SilkS" user "Ref Des/Silkscreen Top")
		(7 "B.SilkS" user "Ref Des/Silkscreen Bottom")
		(1 "F.Mask" user "Board Geometry/Soldermask Top")
		(3 "B.Mask" user "Board Geometry/Soldermask Bottom")
		(17 "Dwgs.User" user "User.Drawings")
		(19 "Cmts.User" user "User.Comments")
		(21 "Eco1.User" user "User.Eco1")
		(23 "Eco2.User" user "User.Eco2")
		(25 "Edge.Cuts" user "Board Geometry/Outline")
		(27 "Margin" user)
		(31 "F.CrtYd" user "Package Geometry/Place Bound Top")
		(29 "B.CrtYd" user "Package Geometry/Place Bound Bottom")
		(35 "F.Fab" user "Ref Des/Assembly Top")
		(33 "B.Fab" user "Ref Des/Assembly Bottom")
	)
	(footprint ""
		(layer "F.Cu")
		(at 123.248674 -161.238184 180)
		(property "Reference" "R643"
			(at -27.988006 -46.909736 0)
			(unlocked yes)
			(layer "F.SilkS")
			(effects
				(font
					(size 0.7874 0.5842)
					(thickness 0.1524)
				)
				(justify left)
			)
		)
		(property "Value" ""
			(at 0 0 180)
			(layer "F.Fab")
			(effects
				(font
					(size 1.27 1.27)
				)
			)
		)
		(duplicate_pad_numbers_are_jumpers no)
		(fp_line
			(start 0.7874 0.4064)
			(end -0.7874 0.4064)
			(stroke
				(width 0.1524)
				(type default)
			)
			(layer "F.SilkS")
		)
		(fp_line
			(start 0.7874 -0.4064)
			(end 0.7874 0.4064)
			(stroke
				(width 0.1524)
				(type default)
			)
			(layer "F.SilkS")
		)
		(fp_line
			(start -0.7874 0.4064)
			(end -0.7874 -0.4064)
			(stroke
				(width 0.1524)
				(type default)
			)
			(layer "F.SilkS")
		)
		(fp_line
			(start -0.7874 -0.4064)
			(end 0.7874 -0.4064)
			(stroke
				(width 0.1524)
				(type default)
			)
			(layer "F.SilkS")
		)
		(fp_poly
			(pts
				(xy -0.508 0.2794) (xy -0.508 0.2286) (xy -0.635 0.2286) (xy -0.635 -0.254) (xy -0.5334 -0.254)
				(xy -0.5334 -0.2794) (xy 0.5334 -0.2794) (xy 0.5334 -0.254) (xy 0.635 -0.254) (xy 0.635 0.254) (xy 0.5334 0.254)
				(xy 0.5334 0.2794)
			)
			(stroke
				(width 0)
				(type default)
			)
			(fill no)
			(layer "F.CrtYd")
		)
		(pad "1" smd rect
			(at 0.40005 0 180)
			(size 0.4572 0.508)
			(layers "F.Cu" "F.Mask" "F.Paste")
			(net "I2C_PSU1_SCL")
		)
		(pad "2" smd rect
			(at -0.40005 0 180)
			(size 0.4572 0.508)
			(layers "F.Cu" "F.Mask" "F.Paste")
			(net "I2C_PSU1_SCL_MOS")
		)
	)
	(footprint ""
		(layer "F.Cu")
		(at 139.02436 -121.070624 -90)
		(property "Reference" "C6"
			(at -2.198116 -0.025146 90)
			(unlocked yes)
			(layer "F.SilkS")
			(effects
				(font
					(size 0.7874 0.5842)
					(thickness 0.1524)
				)
			)
		)
		(property "Value" ""
			(at 0 0 270)
			(layer "F.Fab")
			(effects
				(font
					(size 1.27 1.27)
				)
			)
		)
		(duplicate_pad_numbers_are_jumpers no)
		(fp_line
			(start -1.2954 0.5842)
			(end -1.2954 -0.5842)
			(stroke
				(width 0.1524)
				(type default)
			)
			(layer "F.SilkS")
		)
		(fp_line
			(start 1.2954 0.5842)
			(end -1.2954 0.5842)
			(stroke
				(width 0.1524)
				(type default)
			)
			(layer "F.SilkS")
		)
		(fp_line
			(start -1.2954 -0.5842)
			(end 1.2954 -0.5842)
			(stroke
				(width 0.1524)
				(type default)
			)
			(layer "F.SilkS")
		)
		(fp_line
			(start 0 -0.5842)
			(end 0 0.5842)
			(stroke
				(width 0.1524)
				(type default)
			)
			(layer "F.SilkS")
		)
		(fp_line
			(start 1.2954 -0.5842)
			(end 1.2954 0.5842)
			(stroke
				(width 0.1524)
				(type default)
			)
			(layer "F.SilkS")
		)
		(fp_poly
			(pts
				(xy 0.8636 -0.4572) (xy 0.8636 -0.3556) (xy 1.143 -0.3556) (xy 1.143 0.3556) (xy 0.8636 0.3556)
				(xy 0.8636 0.4572) (xy -0.8636 0.4572) (xy -0.8636 0.3556) (xy -1.143 0.3556) (xy -1.143 -0.3556)
				(xy -0.8636 -0.3556) (xy -0.8636 -0.4572)
			)
			(stroke
				(width 0)
				(type default)
			)
			(fill no)
			(layer "F.CrtYd")
		)
		(fp_line
			(start -0.884936 0.504952)
			(end -0.884936 -0.504952)
			(stroke
				(width 0.1)
				(type default)
			)
			(layer "F.Fab")
		)
		(fp_line
			(start 0.884936 0.504952)
			(end -0.884936 0.504952)
			(stroke
				(width 0.1)
				(type default)
			)
			(layer "F.Fab")
		)
		(fp_line
			(start -0.884936 -0.504952)
			(end 0.884936 -0.504952)
			(stroke
				(width 0.1)
				(type default)
			)
			(layer "F.Fab")
		)
		(fp_line
			(start 0.884936 -0.504952)
			(end 0.884936 0.504952)
			(stroke
				(width 0.1)
				(type default)
			)
			(layer "F.Fab")
		)
		(pad "1" smd rect
			(at 0.7366 0)
			(size 0.7112 0.8128)
			(layers "F.Cu" "F.Mask" "F.Paste")
			(net "P1V5_CLK_NODE1")
		)
		(pad "2" smd rect
			(at -0.7366 0)
			(size 0.7112 0.8128)
			(layers "F.Cu" "F.Mask" "F.Paste")
			(net "GND")
		)
	)
	(footprint ""
		(layer "F.Cu")
		(at 63.0047 -170.630088)
		(property "Reference" "C619"
			(at -9.834626 131.070096 0)
			(unlocked yes)
			(layer "F.SilkS")
			(effects
				(font
					(size 0.7874 0.5842)
					(thickness 0.1524)
				)
				(justify left)
			)
		)
		(property "Value" ""
			(at 0 0 0)
			(layer "F.Fab")
			(effects
				(font
					(size 1.27 1.27)
				)
			)
		)
		(duplicate_pad_numbers_are_jumpers no)
		(fp_line
			(start -0.7874 -0.4064)
			(end 0.7874 -0.4064)
			(stroke
				(width 0.1524)
				(type default)
			)
			(layer "F.SilkS")
		)
		(fp_line
			(start -0.7874 0.4064)
			(end -0.7874 -0.4064)
			(stroke
				(width 0.1524)
				(type default)
			)
			(layer "F.SilkS")
		)
		(fp_line
			(start 0 0.381)
			(end 0 -0.381)
			(stroke
				(width 0.1524)
				(type default)
			)
			(layer "F.SilkS")
		)
		(fp_line
			(start 0.7874 -0.4064)
			(end 0.7874 0.4064)
			(stroke
				(width 0.1524)
				(type default)
			)
			(layer "F.SilkS")
		)
		(fp_line
			(start 0.7874 0.4064)
			(end -0.7874 0.4064)
			(stroke
				(width 0.1524)
				(type default)
			)
			(layer "F.SilkS")
		)
		(fp_poly
			(pts
				(xy -0.5334 0.254) (xy -0.635 0.254) (xy -0.635 0.2286) (xy -0.635 -0.254) (xy -0.5334 -0.254) (xy -0.5334 -0.2794)
				(xy 0.5334 -0.2794) (xy 0.5334 -0.254) (xy 0.635 -0.254) (xy 0.635 0.254) (xy 0.5334 0.254) (xy 0.5334 0.2794)
				(xy -0.508 0.2794) (xy -0.5334 0.2794)
			)
			(stroke
				(width 0)
				(type default)
			)
			(fill no)
			(layer "F.CrtYd")
		)
		(pad "1" smd rect
			(at 0.40005 0)
			(size 0.4572 0.508)
			(layers "F.Cu" "F.Mask" "F.Paste")
			(net "P3V3_NODE1")
		)
		(pad "2" smd rect
			(at -0.40005 0)
			(size 0.4572 0.508)
			(layers "F.Cu" "F.Mask" "F.Paste")
			(net "GND")
		)
	)
	(footprint ""
		(layer "F.Cu")
		(at 82.342228 -133.213094 -90)
		(property "Reference" "D32"
			(at 5.3213 2.271522 90)
			(unlocked yes)
			(layer "F.SilkS")
			(effects
				(font
					(size 0.7874 0.5842)
					(thickness 0.1524)
				)
				(justify left)
			)
		)
		(property "Value" ""
			(at 0 0 270)
			(layer "F.Fab")
			(effects
				(font
					(size 1.27 1.27)
				)
			)
		)
		(duplicate_pad_numbers_are_jumpers no)
		(fp_line
			(start -1.3208 0.5588)
			(end -1.3208 -0.5588)
			(stroke
				(width 0.1524)
				(type default)
			)
			(layer "F.SilkS")
		)
		(fp_line
			(start 1.3208 0.5588)
			(end -1.3208 0.5588)
			(stroke
				(width 0.1524)
				(type default)
			)
			(layer "F.SilkS")
		)
		(fp_line
			(start 1.6256 0.5588)
			(end 1.6256 -0.5588)
			(stroke
				(width 0.1524)
				(type default)
			)
			(layer "F.SilkS")
		)
		(fp_line
			(start 1.778 0.5588)
			(end 1.3208 0.5588)
			(stroke
				(width 0.1524)
				(type default)
			)
			(layer "F.SilkS")
		)
		(fp_line
			(start -1.3208 -0.5588)
			(end 1.3208 -0.5588)
			(stroke
				(width 0.1524)
				(type default)
			)
			(layer "F.SilkS")
		)
		(fp_line
			(start 1.3208 -0.5588)
			(end 1.3208 0.5588)
			(stroke
				(width 0.1524)
				(type default)
			)
			(layer "F.SilkS")
		)
		(fp_line
			(start 1.4732 -0.5588)
			(end 1.4732 0.5588)
			(stroke
				(width 0.1524)
				(type default)
			)
			(layer "F.SilkS")
		)
		(fp_line
			(start 1.778 -0.5588)
			(end 1.778 0.5588)
			(stroke
				(width 0.1524)
				(type default)
			)
			(layer "F.SilkS")
		)
		(fp_line
			(start 1.778 -0.5588)
			(end 1.3208 -0.5588)
			(stroke
				(width 0.1524)
				(type default)
			)
			(layer "F.SilkS")
		)
		(fp_circle
			(center 2.4384 0)
			(end 2.4384 -0.413512)
			(stroke
				(width 0.1524)
				(type default)
			)
			(fill no)
			(layer "F.SilkS")
		)
		(fp_rect
			(start -1.1684 0.508)
			(end 1.1684 -0.508)
			(stroke
				(width 0)
				(type default)
			)
			(fill no)
			(layer "F.CrtYd")
		)
		(fp_text user "-"
			(at 2.687574 -0.35052 270)
			(unlocked yes)
			(layer "F.SilkS")
			(effects
				(font
					(size 0.7874 0.5842)
					(thickness 0.1524)
				)
				(justify left)
			)
		)
		(pad "A" smd rect
			(at -0.750062 0 270)
			(size 0.8128 0.8128)
			(layers "F.Cu" "F.Mask" "F.Paste")
			(net "P3V3_NODE1")
		)
		(pad "C" smd rect
			(at 0.750062 0 270)
			(size 0.8128 0.8128)
			(layers "F.Cu" "F.Mask" "F.Paste")
			(net "N53313464")
		)
	)
	(footprint ""
		(layer "F.Cu")
		(at 18.21942 -45.508926 -90)
		(property "Reference" "R634"
			(at 7.797038 0.840994 90)
			(unlocked yes)
			(layer "F.SilkS")
			(effects
				(font
					(size 0.7874 0.5842)
					(thickness 0.1524)
				)
				(justify left)
			)
		)
		(property "Value" ""
			(at 0 0 270)
			(layer "F.Fab")
			(effects
				(font
					(size 1.27 1.27)
				)
			)
		)
		(duplicate_pad_numbers_are_jumpers no)
		(fp_line
			(start -0.7874 0.4064)
			(end -0.7874 -0.4064)
			(stroke
				(width 0.1524)
				(type default)
			)
			(layer "F.SilkS")
		)
		(fp_line
			(start 0.7874 0.4064)
			(end -0.7874 0.4064)
			(stroke
				(width 0.1524)
				(type default)
			)
			(layer "F.SilkS")
		)
		(fp_line
			(start -0.7874 -0.4064)
			(end 0.7874 -0.4064)
			(stroke
				(width 0.1524)
				(type default)
			)
			(layer "F.SilkS")
		)
		(fp_line
			(start 0.7874 -0.4064)
			(end 0.7874 0.4064)
			(stroke
				(width 0.1524)
				(type default)
			)
			(layer "F.SilkS")
		)
		(fp_poly
			(pts
				(xy -0.508 0.2794) (xy -0.508 0.2286) (xy -0.635 0.2286) (xy -0.635 -0.254) (xy -0.5334 -0.254)
				(xy -0.5334 -0.2794) (xy 0.5334 -0.2794) (xy 0.5334 -0.254) (xy 0.635 -0.254) (xy 0.635 0.254) (xy 0.5334 0.254)
				(xy 0.5334 0.2794)
			)
			(stroke
				(width 0)
				(type default)
			)
			(fill no)
			(layer "F.CrtYd")
		)
		(pad "1" smd rect
			(at 0.40005 0 270)
			(size 0.4572 0.508)
			(layers "F.Cu" "F.Mask" "F.Paste")
			(net "P5V_CRT")
		)
		(pad "2" smd rect
			(at -0.40005 0 270)
			(size 0.4572 0.508)
			(layers "F.Cu" "F.Mask" "F.Paste")
			(net "I2C_VIDREAR_5V_SDA")
		)
	)
	(footprint ""
		(layer "F.Cu")
		(at 58.097166 -96.709992 -90)
		(property "Reference" "R47"
			(at 54.98719 -28.440888 90)
			(unlocked yes)
			(layer "F.SilkS")
			(effects
				(font
					(size 0.7874 0.5842)
					(thickness 0.1524)
				)
				(justify left)
			)
		)
		(property "Value" ""
			(at 0 0 270)
			(layer "F.Fab")
			(effects
				(font
					(size 1.27 1.27)
				)
			)
		)
		(duplicate_pad_numbers_are_jumpers no)
		(fp_line
			(start -0.7874 0.4064)
			(end -0.7874 -0.4064)
			(stroke
				(width 0.1524)
				(type default)
			)
			(layer "F.SilkS")
		)
		(fp_line
			(start 0.7874 0.4064)
			(end -0.7874 0.4064)
			(stroke
				(width 0.1524)
				(type default)
			)
			(layer "F.SilkS")
		)
		(fp_line
			(start -0.7874 -0.4064)
			(end 0.7874 -0.4064)
			(stroke
				(width 0.1524)
				(type default)
			)
			(layer "F.SilkS")
		)
		(fp_line
			(start 0.7874 -0.4064)
			(end 0.7874 0.4064)
			(stroke
				(width 0.1524)
				(type default)
			)
			(layer "F.SilkS")
		)
		(fp_poly
			(pts
				(xy -0.508 0.2794) (xy -0.508 0.2286) (xy -0.635 0.2286) (xy -0.635 -0.254) (xy -0.5334 -0.254)
				(xy -0.5334 -0.2794) (xy 0.5334 -0.2794) (xy 0.5334 -0.254) (xy 0.635 -0.254) (xy 0.635 0.254) (xy 0.5334 0.254)
				(xy 0.5334 0.2794)
			)
			(stroke
				(width 0)
				(type default)
			)
			(fill no)
			(layer "F.CrtYd")
		)
		(pad "1" smd rect
			(at 0.40005 0 270)
			(size 0.4572 0.508)
			(layers "F.Cu" "F.Mask" "F.Paste")
			(net "PU_CPU_NODE1_DFX_GPIO_GRP1_6")
		)
		(pad "2" smd rect
			(at -0.40005 0 270)
			(size 0.4572 0.508)
			(layers "F.Cu" "F.Mask" "F.Paste")
			(net "P1V8_NODE1")
		)
	)
	(footprint ""
		(layer "F.Cu")
		(at 149.8092 -174.112936 90)
		(property "Reference" "R1261"
			(at 0.637032 0.956564 90)
			(unlocked yes)
			(layer "F.SilkS")
			(effects
				(font
					(size 0.7874 0.5842)
					(thickness 0.1524)
				)
				(justify left)
			)
		)
		(property "Value" ""
			(at 0 0 90)
			(layer "F.Fab")
			(effects
				(font
					(size 1.27 1.27)
				)
			)
		)
		(duplicate_pad_numbers_are_jumpers no)
		(fp_line
			(start 0.7874 -0.4064)
			(end 0.7874 0.4064)
			(stroke
				(width 0.1524)
				(type default)
			)
			(layer "F.SilkS")
		)
		(fp_line
			(start -0.7874 -0.4064)
			(end 0.7874 -0.4064)
			(stroke
				(width 0.1524)
				(type default)
			)
			(layer "F.SilkS")
		)
		(fp_line
			(start 0.7874 0.4064)
			(end -0.7874 0.4064)
			(stroke
				(width 0.1524)
				(type default)
			)
			(layer "F.SilkS")
		)
		(fp_line
			(start -0.7874 0.4064)
			(end -0.7874 -0.4064)
			(stroke
				(width 0.1524)
				(type default)
			)
			(layer "F.SilkS")
		)
		(fp_poly
			(pts
				(xy -0.508 0.2794) (xy -0.508 0.2286) (xy -0.635 0.2286) (xy -0.635 -0.254) (xy -0.5334 -0.254)
				(xy -0.5334 -0.2794) (xy 0.5334 -0.2794) (xy 0.5334 -0.254) (xy 0.635 -0.254) (xy 0.635 0.254) (xy 0.5334 0.254)
				(xy 0.5334 0.2794)
			)
			(stroke
				(width 0)
				(type default)
			)
			(fill no)
			(layer "F.CrtYd")
		)
		(pad "1" smd rect
			(at 0.40005 0 90)
			(size 0.4572 0.508)
			(layers "F.Cu" "F.Mask" "F.Paste")
			(net "CPLD_UART_RI_P3_N")
		)
		(pad "2" smd rect
			(at -0.40005 0 90)
			(size 0.4572 0.508)
			(layers "F.Cu" "F.Mask" "F.Paste")
			(net "P3V3_NODE1")
		)
	)
	(footprint ""
		(layer "F.Cu")
		(at 84.350352 -137.033762 -90)
		(property "Reference" "R1097"
			(at -2.512314 -4.28879 90)
			(unlocked yes)
			(layer "F.SilkS")
			(effects
				(font
					(size 0.7874 0.5842)
					(thickness 0.1524)
				)
				(justify left)
			)
		)
		(property "Value" ""
			(at 0 0 270)
			(layer "F.Fab")
			(effects
				(font
					(size 1.27 1.27)
				)
			)
		)
		(duplicate_pad_numbers_are_jumpers no)
		(fp_line
			(start -0.7874 0.4064)
			(end -0.7874 -0.4064)
			(stroke
				(width 0.1524)
				(type default)
			)
			(layer "F.SilkS")
		)
		(fp_line
			(start 0.7874 0.4064)
			(end -0.7874 0.4064)
			(stroke
				(width 0.1524)
				(type default)
			)
			(layer "F.SilkS")
		)
		(fp_line
			(start -0.7874 -0.4064)
			(end 0.7874 -0.4064)
			(stroke
				(width 0.1524)
				(type default)
			)
			(layer "F.SilkS")
		)
		(fp_line
			(start 0.7874 -0.4064)
			(end 0.7874 0.4064)
			(stroke
				(width 0.1524)
				(type default)
			)
			(layer "F.SilkS")
		)
		(fp_poly
			(pts
				(xy -0.508 0.2794) (xy -0.508 0.2286) (xy -0.635 0.2286) (xy -0.635 -0.254) (xy -0.5334 -0.254)
				(xy -0.5334 -0.2794) (xy 0.5334 -0.2794) (xy 0.5334 -0.254) (xy 0.635 -0.254) (xy 0.635 0.254) (xy 0.5334 0.254)
				(xy 0.5334 0.2794)
			)
			(stroke
				(width 0)
				(type default)
			)
			(fill no)
			(layer "F.CrtYd")
		)
		(pad "1" smd rect
			(at 0.40005 0 270)
			(size 0.4572 0.508)
			(layers "F.Cu" "F.Mask" "F.Paste")
			(net "P1V26_STB_NODE1_ADJ_S")
		)
		(pad "2" smd rect
			(at -0.40005 0 270)
			(size 0.4572 0.508)
			(layers "F.Cu" "F.Mask" "F.Paste")
			(net "P1V26_BMC_NODE1_ADJ")
		)
	)
	(footprint ""
		(layer "F.Cu")
		(at 24.6761 -143.307308 180)
		(property "Reference" "Q15"
			(at -3.94462 -2.02438 0)
			(unlocked yes)
			(layer "F.SilkS")
			(effects
				(font
					(size 0.7874 0.5842)
					(thickness 0.1524)
				)
				(justify left)
			)
		)
		(property "Value" ""
			(at 0 0 180)
			(layer "F.Fab")
			(effects
				(font
					(size 1.27 1.27)
				)
			)
		)
		(duplicate_pad_numbers_are_jumpers no)
		(fp_line
			(start 3.3528 1.651)
			(end 3.3528 -1.651)
			(stroke
				(width 0.1524)
				(type default)
			)
			(layer "F.SilkS")
		)
		(fp_line
			(start 3.3528 -1.651)
			(end -3.3528 -1.651)
			(stroke
				(width 0.1524)
				(type default)
			)
			(layer "F.SilkS")
		)
		(fp_line
			(start -3.3528 1.651)
			(end 3.3528 1.651)
			(stroke
				(width 0.1524)
				(type default)
			)
			(layer "F.SilkS")
		)
		(fp_line
			(start -3.3528 -1.651)
			(end -3.3528 1.651)
			(stroke
				(width 0.1524)
				(type default)
			)
			(layer "F.SilkS")
		)
		(fp_poly
			(pts
				(xy -3.048 3.8354) (xy -3.048 1.8796) (xy -3.3528 1.8796) (xy -3.3528 -1.8796) (xy -1.905 -1.8796)
				(xy -1.905 -3.8354) (xy 1.905 -3.8354) (xy 1.905 -1.8796) (xy 3.3528 -1.8796) (xy 3.3528 1.8796)
				(xy 3.048 1.8796) (xy 3.048 3.8354)
			)
			(stroke
				(width 0)
				(type default)
			)
			(fill no)
			(layer "F.CrtYd")
		)
		(pad "1" smd rect
			(at -2.286 2.8321 180)
			(size 1.4986 2.0066)
			(layers "F.Cu" "F.Mask" "F.Paste")
			(net "LAN1_CTRL_P1V9")
		)
		(pad "2" smd rect
			(at 0 2.8321 180)
			(size 1.4986 2.0066)
			(layers "F.Cu" "F.Mask" "F.Paste")
			(net "P1V9_LAN1")
		)
		(pad "3" smd rect
			(at 2.286 2.8321 180)
			(size 1.4986 2.0066)
			(layers "F.Cu" "F.Mask" "F.Paste")
			(net "P3V3_NODE1")
		)
		(pad "4" smd rect
			(at 0 -2.8321 270)
			(size 2.0066 3.81)
			(layers "F.Cu" "F.Mask" "F.Paste")
			(net "P1V9_LAN1")
		)
	)
	(footprint ""
		(layer "F.Cu")
		(at 23.84171 -108.443522 180)
		(property "Reference" "PC66"
			(at -2.78511 0.012446 0)
			(unlocked yes)
			(layer "F.SilkS")
			(effects
				(font
					(size 0.7874 0.5842)
					(thickness 0.1524)
				)
				(justify left)
			)
		)
		(property "Value" ""
			(at 0 0 180)
			(layer "F.Fab")
			(effects
				(font
					(size 1.27 1.27)
				)
			)
		)
		(duplicate_pad_numbers_are_jumpers no)
		(fp_line
			(start 1.905 0.8636)
			(end -1.905 0.8636)
			(stroke
				(width 0.1524)
				(type default)
			)
			(layer "F.SilkS")
		)
		(fp_line
			(start 1.905 -0.8636)
			(end 1.905 0.8636)
			(stroke
				(width 0.1524)
				(type default)
			)
			(layer "F.SilkS")
		)
		(fp_line
			(start 0 0.8382)
			(end 0 -0.8382)
			(stroke
				(width 0.1524)
				(type default)
			)
			(layer "F.SilkS")
		)
		(fp_line
			(start -1.905 0.8636)
			(end -1.905 -0.8636)
			(stroke
				(width 0.1524)
				(type default)
			)
			(layer "F.SilkS")
		)
		(fp_line
			(start -1.905 -0.8636)
			(end 1.905 -0.8636)
			(stroke
				(width 0.1524)
				(type default)
			)
			(layer "F.SilkS")
		)
		(fp_rect
			(start -1.524 0.7366)
			(end 1.524 -0.7366)
			(stroke
				(width 0)
				(type default)
			)
			(fill no)
			(layer "F.CrtYd")
		)
		(pad "1" smd rect
			(at 0.94996 0 180)
			(size 1.1176 1.3716)
			(layers "F.Cu" "F.Mask" "F.Paste")
			(net "P1V05_NODE1")
		)
		(pad "2" smd rect
			(at -0.94996 0 180)
			(size 1.1176 1.3716)
			(layers "F.Cu" "F.Mask" "F.Paste")
			(net "GND")
		)
	)
)
